(kicad_pcb
	(version 20260206)
	(generator "pcbnew")
	(generator_version "10.0")
	(general
		(thickness 1.6)
		(legacy_teardrops no)
	)
	(paper "A4")
	(title_block
		(title "04192023_DAF0TMB3IC0_F0TG_MB_C_brd_V02_OCP.brd")
		(comment 1 "Grand Teton / footprints 865-871 of 8354")
	)
	(layers
		(0 "F.Cu" signal "TOP")
		(4 "In1.Cu" signal "GND")
		(6 "In2.Cu" signal "IN1")
		(8 "In3.Cu" signal "GND1")
		(10 "In4.Cu" signal "IN2")
		(12 "In5.Cu" signal "GND2")
		(14 "In6.Cu" signal "IN3")
		(16 "In7.Cu" signal "GND3")
		(18 "In8.Cu" signal "VCC")
		(20 "In9.Cu" signal "VCC1")
		(22 "In10.Cu" signal "GND4")
		(24 "In11.Cu" signal "IN4")
		(26 "In12.Cu" signal "GND5")
		(28 "In13.Cu" signal "IN5")
		(30 "In14.Cu" signal "GND6")
		(32 "In15.Cu" signal "IN6")
		(34 "In16.Cu" signal "GND7")
		(2 "B.Cu" signal "BOTTOM")
		(9 "F.Adhes" user "F.Adhesive")
		(11 "B.Adhes" user "B.Adhesive")
		(13 "F.Paste" user "Package Geometry/Pastemask Top")
		(15 "B.Paste" user "Package Geometry/Pastemask Bottom")
		(5 "F.SilkS" user "Ref Des/Silkscreen Top")
		(7 "B.SilkS" user "Ref Des/Silkscreen Bottom")
		(1 "F.Mask" user "Board Geometry/Soldermask Top")
		(3 "B.Mask" user "Board Geometry/Soldermask Bottom")
		(17 "Dwgs.User" user "User.Drawings")
		(19 "Cmts.User" user "User.Comments")
		(21 "Eco1.User" user "User.Eco1")
		(23 "Eco2.User" user "User.Eco2")
		(25 "Edge.Cuts" user "Board Geometry/Outline")
		(27 "Margin" user)
		(31 "F.CrtYd" user "Package Geometry/Place Bound Top")
		(29 "B.CrtYd" user "Package Geometry/Place Bound Bottom")
		(35 "F.Fab" user "Ref Des/Assembly Top")
		(33 "B.Fab" user "Ref Des/Assembly Bottom")
	)
	(footprint ""
		(layer "F.Cu")
		(at 32.336994 -133.83895 180)
		(property "Reference" "U248"
			(at 1.415288 -2.52349 0)
			(unlocked yes)
			(layer "F.SilkS")
			(effects
				(font
					(size 0.7874 0.5842)
					(thickness 0.1524)
				)
				(justify left)
			)
		)
		(property "Value" ""
			(at 0 0 180)
			(layer "F.Fab")
			(effects
				(font
					(size 1.27 1.27)
				)
			)
		)
		(duplicate_pad_numbers_are_jumpers no)
		(fp_line
			(start 1.4986 1.100074)
			(end -1.4986 1.100074)
			(stroke
				(width 0.1524)
				(type default)
			)
			(layer "F.SilkS")
		)
		(fp_line
			(start 1.4986 -1.100074)
			(end 1.4986 1.100074)
			(stroke
				(width 0.1524)
				(type default)
			)
			(layer "F.SilkS")
		)
		(fp_line
			(start -1.4986 1.100074)
			(end -1.4986 -1.100074)
			(stroke
				(width 0.1524)
				(type default)
			)
			(layer "F.SilkS")
		)
		(fp_line
			(start -1.4986 -1.100074)
			(end 1.4986 -1.100074)
			(stroke
				(width 0.1524)
				(type default)
			)
			(layer "F.SilkS")
		)
		(fp_poly
			(pts
				(xy -0.956056 -1.274064) (xy -1.252728 -1.827784) (xy -0.627888 -1.827784)
			)
			(stroke
				(width 0)
				(type default)
			)
			(fill yes)
			(layer "F.SilkS")
		)
		(fp_line
			(start 0.67437 1.100074)
			(end -0.67437 1.100074)
			(stroke
				(width 0.1)
				(type default)
			)
			(layer "F.Fab")
		)
		(fp_line
			(start 0.67437 -1.100074)
			(end 0.67437 1.100074)
			(stroke
				(width 0.1)
				(type default)
			)
			(layer "F.Fab")
		)
		(fp_line
			(start -0.67437 1.100074)
			(end -0.67437 -1.100074)
			(stroke
				(width 0.1)
				(type default)
			)
			(layer "F.Fab")
		)
		(fp_line
			(start -0.67437 -1.100074)
			(end 0.67437 -1.100074)
			(stroke
				(width 0.1)
				(type default)
			)
			(layer "F.Fab")
		)
		(fp_poly
			(pts
				(xy -2.20472 -0.338328) (xy -2.20472 -0.963168) (xy -1.651 -0.635)
			)
			(stroke
				(width 0)
				(type default)
			)
			(fill yes)
			(layer "F.Fab")
		)
		(pad "1" smd rect
			(at -0.889 -0.649986 180)
			(size 1.016 0.381)
			(layers "F.Cu" "F.Mask" "F.Paste")
			(net "GPU_FPGA_READY_R_N")
		)
		(pad "2" smd rect
			(at -0.889 0 180)
			(size 1.016 0.381)
			(layers "F.Cu" "F.Mask" "F.Paste")
			(net "CLK_GEN2_GPU_FPGA_OE_R2_N")
		)
		(pad "3" smd rect
			(at -0.889 0.649986 180)
			(size 1.016 0.381)
			(layers "F.Cu" "F.Mask" "F.Paste")
			(net "GND")
		)
		(pad "4" smd rect
			(at 0.889 0.649986 180)
			(size 1.016 0.381)
			(layers "F.Cu" "F.Mask" "F.Paste")
			(net "CLK_GEN2_GPU_FPGA_OE_OR_N")
		)
		(pad "5" smd rect
			(at 0.889 -0.649986 180)
			(size 1.016 0.381)
			(layers "F.Cu" "F.Mask" "F.Paste")
			(net "P3V3_AUX")
		)
	)
	(footprint ""
		(layer "F.Cu")
		(at 103.170736 -127.787654 -90)
		(property "Reference" "R1442"
			(at 0 0 270)
			(layer "F.SilkS")
			(hide yes)
			(effects
				(font
					(size 1.27 1.27)
				)
			)
		)
		(property "Value" ""
			(at 0 0 270)
			(layer "F.Fab")
			(effects
				(font
					(size 1.27 1.27)
				)
			)
		)
		(duplicate_pad_numbers_are_jumpers no)
		(fp_line
			(start -0.7874 0.4064)
			(end -0.7874 -0.4064)
			(stroke
				(width 0.1524)
				(type default)
			)
			(layer "F.SilkS")
		)
		(fp_line
			(start 0.7874 0.4064)
			(end -0.7874 0.4064)
			(stroke
				(width 0.1524)
				(type default)
			)
			(layer "F.SilkS")
		)
		(fp_line
			(start -0.7874 -0.4064)
			(end 0.7874 -0.4064)
			(stroke
				(width 0.1524)
				(type default)
			)
			(layer "F.SilkS")
		)
		(fp_line
			(start 0.7874 -0.4064)
			(end 0.7874 0.4064)
			(stroke
				(width 0.1524)
				(type default)
			)
			(layer "F.SilkS")
		)
		(fp_line
			(start -0.67945 0.3048)
			(end -0.67945 -0.305054)
			(stroke
				(width 0.1)
				(type default)
			)
			(layer "F.Fab")
		)
		(fp_line
			(start -0.12065 0.3048)
			(end -0.67945 0.3048)
			(stroke
				(width 0.1)
				(type default)
			)
			(layer "F.Fab")
		)
		(fp_line
			(start 0.120396 0.3048)
			(end 0.120396 0.2794)
			(stroke
				(width 0.1)
				(type default)
			)
			(layer "F.Fab")
		)
		(fp_line
			(start 0.67945 0.3048)
			(end 0.120396 0.3048)
			(stroke
				(width 0.1)
				(type default)
			)
			(layer "F.Fab")
		)
		(fp_line
			(start -0.12065 0.2794)
			(end -0.12065 0.3048)
			(stroke
				(width 0.1)
				(type default)
			)
			(layer "F.Fab")
		)
		(fp_line
			(start 0.120396 0.2794)
			(end -0.12065 0.2794)
			(stroke
				(width 0.1)
				(type default)
			)
			(layer "F.Fab")
		)
		(fp_line
			(start -0.12065 -0.2794)
			(end 0.12065 -0.2794)
			(stroke
				(width 0.1)
				(type default)
			)
			(layer "F.Fab")
		)
		(fp_line
			(start 0.12065 -0.2794)
			(end 0.12065 -0.3048)
			(stroke
				(width 0.1)
				(type default)
			)
			(layer "F.Fab")
		)
		(fp_line
			(start 0.12065 -0.3048)
			(end 0.67945 -0.3048)
			(stroke
				(width 0.1)
				(type default)
			)
			(layer "F.Fab")
		)
		(fp_line
			(start 0.67945 -0.3048)
			(end 0.67945 0.3048)
			(stroke
				(width 0.1)
				(type default)
			)
			(layer "F.Fab")
		)
		(fp_line
			(start -0.67945 -0.305054)
			(end -0.12065 -0.305054)
			(stroke
				(width 0.1)
				(type default)
			)
			(layer "F.Fab")
		)
		(fp_line
			(start -0.12065 -0.305054)
			(end -0.12065 -0.2794)
			(stroke
				(width 0.1)
				(type default)
			)
			(layer "F.Fab")
		)
		(pad "1" smd circle
			(at -0.40005 0 270)
			(size 0 0)
			(layers "F.Cu" "F.Mask" "F.Paste")
			(net "P12V_MEM_CPU0")
		)
		(pad "2" smd circle
			(at 0.40005 0 270)
			(size 0 0)
			(layers "F.Cu" "F.Mask" "F.Paste")
			(net "PWRGD_P12V_MEM_CPU0_EN")
		)
	)
	(footprint ""
		(layer "F.Cu")
		(at 34.665158 -173.55566)
		(property "Reference" "R1294"
			(at 0 0 0)
			(layer "F.SilkS")
			(hide yes)
			(effects
				(font
					(size 1.27 1.27)
				)
			)
		)
		(property "Value" ""
			(at 0 0 0)
			(layer "F.Fab")
			(effects
				(font
					(size 1.27 1.27)
				)
			)
		)
		(duplicate_pad_numbers_are_jumpers no)
		(fp_line
			(start -0.7874 -0.4064)
			(end 0.7874 -0.4064)
			(stroke
				(width 0.1524)
				(type default)
			)
			(layer "F.SilkS")
		)
		(fp_line
			(start -0.7874 0.4064)
			(end -0.7874 -0.4064)
			(stroke
				(width 0.1524)
				(type default)
			)
			(layer "F.SilkS")
		)
		(fp_line
			(start 0.7874 -0.4064)
			(end 0.7874 0.4064)
			(stroke
				(width 0.1524)
				(type default)
			)
			(layer "F.SilkS")
		)
		(fp_line
			(start 0.7874 0.4064)
			(end -0.7874 0.4064)
			(stroke
				(width 0.1524)
				(type default)
			)
			(layer "F.SilkS")
		)
		(fp_line
			(start -0.67945 -0.305054)
			(end -0.12065 -0.305054)
			(stroke
				(width 0.1)
				(type default)
			)
			(layer "F.Fab")
		)
		(fp_line
			(start -0.67945 0.3048)
			(end -0.67945 -0.305054)
			(stroke
				(width 0.1)
				(type default)
			)
			(layer "F.Fab")
		)
		(fp_line
			(start -0.12065 -0.305054)
			(end -0.12065 -0.2794)
			(stroke
				(width 0.1)
				(type default)
			)
			(layer "F.Fab")
		)
		(fp_line
			(start -0.12065 -0.2794)
			(end 0.12065 -0.2794)
			(stroke
				(width 0.1)
				(type default)
			)
			(layer "F.Fab")
		)
		(fp_line
			(start -0.12065 0.2794)
			(end -0.12065 0.3048)
			(stroke
				(width 0.1)
				(type default)
			)
			(layer "F.Fab")
		)
		(fp_line
			(start -0.12065 0.3048)
			(end -0.67945 0.3048)
			(stroke
				(width 0.1)
				(type default)
			)
			(layer "F.Fab")
		)
		(fp_line
			(start 0.120396 0.2794)
			(end -0.12065 0.2794)
			(stroke
				(width 0.1)
				(type default)
			)
			(layer "F.Fab")
		)
		(fp_line
			(start 0.120396 0.3048)
			(end 0.120396 0.2794)
			(stroke
				(width 0.1)
				(type default)
			)
			(layer "F.Fab")
		)
		(fp_line
			(start 0.12065 -0.3048)
			(end 0.67945 -0.3048)
			(stroke
				(width 0.1)
				(type default)
			)
			(layer "F.Fab")
		)
		(fp_line
			(start 0.12065 -0.2794)
			(end 0.12065 -0.3048)
			(stroke
				(width 0.1)
				(type default)
			)
			(layer "F.Fab")
		)
		(fp_line
			(start 0.67945 -0.3048)
			(end 0.67945 0.3048)
			(stroke
				(width 0.1)
				(type default)
			)
			(layer "F.Fab")
		)
		(fp_line
			(start 0.67945 0.3048)
			(end 0.120396 0.3048)
			(stroke
				(width 0.1)
				(type default)
			)
			(layer "F.Fab")
		)
		(pad "1" smd rect
			(at -0.40005 0 180)
			(size 0.4572 0.508)
			(layers "F.Cu" "F.Mask" "F.Paste")
			(net "I3C_SPD_DDRAF_CPU1_SDA")
		)
		(pad "2" smd rect
			(at 0.40005 0 180)
			(size 0.4572 0.508)
			(layers "F.Cu" "F.Mask" "F.Paste")
			(net "I3C_SPD_DDRAF_CPU1_LVC1_SDA")
		)
	)
	(footprint ""
		(layer "F.Cu")
		(at 69.457824 -18.932144)
		(property "Reference" "R1302"
			(at 0 0 0)
			(layer "F.SilkS")
			(hide yes)
			(effects
				(font
					(size 1.27 1.27)
				)
			)
		)
		(property "Value" ""
			(at 0 0 0)
			(layer "F.Fab")
			(effects
				(font
					(size 1.27 1.27)
				)
			)
		)
		(duplicate_pad_numbers_are_jumpers no)
		(fp_line
			(start -0.7874 -0.4064)
			(end 0.7874 -0.4064)
			(stroke
				(width 0.1524)
				(type default)
			)
			(layer "F.SilkS")
		)
		(fp_line
			(start -0.7874 0.4064)
			(end -0.7874 -0.4064)
			(stroke
				(width 0.1524)
				(type default)
			)
			(layer "F.SilkS")
		)
		(fp_line
			(start 0.7874 -0.4064)
			(end 0.7874 0.4064)
			(stroke
				(width 0.1524)
				(type default)
			)
			(layer "F.SilkS")
		)
		(fp_line
			(start 0.7874 0.4064)
			(end -0.7874 0.4064)
			(stroke
				(width 0.1524)
				(type default)
			)
			(layer "F.SilkS")
		)
		(fp_line
			(start -0.67945 -0.305054)
			(end -0.12065 -0.305054)
			(stroke
				(width 0.1)
				(type default)
			)
			(layer "F.Fab")
		)
		(fp_line
			(start -0.67945 0.3048)
			(end -0.67945 -0.305054)
			(stroke
				(width 0.1)
				(type default)
			)
			(layer "F.Fab")
		)
		(fp_line
			(start -0.12065 -0.305054)
			(end -0.12065 -0.2794)
			(stroke
				(width 0.1)
				(type default)
			)
			(layer "F.Fab")
		)
		(fp_line
			(start -0.12065 -0.2794)
			(end 0.12065 -0.2794)
			(stroke
				(width 0.1)
				(type default)
			)
			(layer "F.Fab")
		)
		(fp_line
			(start -0.12065 0.2794)
			(end -0.12065 0.3048)
			(stroke
				(width 0.1)
				(type default)
			)
			(layer "F.Fab")
		)
		(fp_line
			(start -0.12065 0.3048)
			(end -0.67945 0.3048)
			(stroke
				(width 0.1)
				(type default)
			)
			(layer "F.Fab")
		)
		(fp_line
			(start 0.120396 0.2794)
			(end -0.12065 0.2794)
			(stroke
				(width 0.1)
				(type default)
			)
			(layer "F.Fab")
		)
		(fp_line
			(start 0.120396 0.3048)
			(end 0.120396 0.2794)
			(stroke
				(width 0.1)
				(type default)
			)
			(layer "F.Fab")
		)
		(fp_line
			(start 0.12065 -0.3048)
			(end 0.67945 -0.3048)
			(stroke
				(width 0.1)
				(type default)
			)
			(layer "F.Fab")
		)
		(fp_line
			(start 0.12065 -0.2794)
			(end 0.12065 -0.3048)
			(stroke
				(width 0.1)
				(type default)
			)
			(layer "F.Fab")
		)
		(fp_line
			(start 0.67945 -0.3048)
			(end 0.67945 0.3048)
			(stroke
				(width 0.1)
				(type default)
			)
			(layer "F.Fab")
		)
		(fp_line
			(start 0.67945 0.3048)
			(end 0.120396 0.3048)
			(stroke
				(width 0.1)
				(type default)
			)
			(layer "F.Fab")
		)
		(pad "1" smd circle
			(at -0.40005 0)
			(size 0 0)
			(layers "F.Cu" "F.Mask" "F.Paste")
			(net "P12V_OCP_V3_2_R")
		)
		(pad "2" smd circle
			(at 0.40005 0)
			(size 0 0)
			(layers "F.Cu" "F.Mask" "F.Paste")
			(net "VSENSE_P12V_INA230_7_INN")
		)
	)
	(footprint ""
		(layer "F.Cu")
		(at 277.352252 -114.70767)
		(property "Reference" "R1089"
			(at 0 0 0)
			(layer "F.SilkS")
			(hide yes)
			(effects
				(font
					(size 1.27 1.27)
				)
			)
		)
		(property "Value" ""
			(at 0 0 0)
			(layer "F.Fab")
			(effects
				(font
					(size 1.27 1.27)
				)
			)
		)
		(duplicate_pad_numbers_are_jumpers no)
		(fp_line
			(start -0.7874 -0.4064)
			(end 0.7874 -0.4064)
			(stroke
				(width 0.1524)
				(type default)
			)
			(layer "F.SilkS")
		)
		(fp_line
			(start -0.7874 0.4064)
			(end -0.7874 -0.4064)
			(stroke
				(width 0.1524)
				(type default)
			)
			(layer "F.SilkS")
		)
		(fp_line
			(start 0.7874 -0.4064)
			(end 0.7874 0.4064)
			(stroke
				(width 0.1524)
				(type default)
			)
			(layer "F.SilkS")
		)
		(fp_line
			(start 0.7874 0.4064)
			(end -0.7874 0.4064)
			(stroke
				(width 0.1524)
				(type default)
			)
			(layer "F.SilkS")
		)
		(fp_line
			(start -0.67945 -0.305054)
			(end -0.12065 -0.305054)
			(stroke
				(width 0.1)
				(type default)
			)
			(layer "F.Fab")
		)
		(fp_line
			(start -0.67945 0.3048)
			(end -0.67945 -0.305054)
			(stroke
				(width 0.1)
				(type default)
			)
			(layer "F.Fab")
		)
		(fp_line
			(start -0.12065 -0.305054)
			(end -0.12065 -0.2794)
			(stroke
				(width 0.1)
				(type default)
			)
			(layer "F.Fab")
		)
		(fp_line
			(start -0.12065 -0.2794)
			(end 0.12065 -0.2794)
			(stroke
				(width 0.1)
				(type default)
			)
			(layer "F.Fab")
		)
		(fp_line
			(start -0.12065 0.2794)
			(end -0.12065 0.3048)
			(stroke
				(width 0.1)
				(type default)
			)
			(layer "F.Fab")
		)
		(fp_line
			(start -0.12065 0.3048)
			(end -0.67945 0.3048)
			(stroke
				(width 0.1)
				(type default)
			)
			(layer "F.Fab")
		)
		(fp_line
			(start 0.120396 0.2794)
			(end -0.12065 0.2794)
			(stroke
				(width 0.1)
				(type default)
			)
			(layer "F.Fab")
		)
		(fp_line
			(start 0.120396 0.3048)
			(end 0.120396 0.2794)
			(stroke
				(width 0.1)
				(type default)
			)
			(layer "F.Fab")
		)
		(fp_line
			(start 0.12065 -0.3048)
			(end 0.67945 -0.3048)
			(stroke
				(width 0.1)
				(type default)
			)
			(layer "F.Fab")
		)
		(fp_line
			(start 0.12065 -0.2794)
			(end 0.12065 -0.3048)
			(stroke
				(width 0.1)
				(type default)
			)
			(layer "F.Fab")
		)
		(fp_line
			(start 0.67945 -0.3048)
			(end 0.67945 0.3048)
			(stroke
				(width 0.1)
				(type default)
			)
			(layer "F.Fab")
		)
		(fp_line
			(start 0.67945 0.3048)
			(end 0.120396 0.3048)
			(stroke
				(width 0.1)
				(type default)
			)
			(layer "F.Fab")
		)
		(pad "1" smd circle
			(at -0.40005 0)
			(size 0 0)
			(layers "F.Cu" "F.Mask" "F.Paste")
			(net "P3V3_AUX")
		)
		(pad "2" smd circle
			(at 0.40005 0)
			(size 0 0)
			(layers "F.Cu" "F.Mask" "F.Paste")
			(net "SMB_SENSOR_M2_P1_3V3AUX_SCL")
		)
	)
	(footprint ""
		(layer "F.Cu")
		(at 390.007348 -16.100298 90)
		(property "Reference" "C1548"
			(at 0 0 90)
			(layer "F.SilkS")
			(hide yes)
			(effects
				(font
					(size 1.27 1.27)
				)
			)
		)
		(property "Value" ""
			(at 0 0 90)
			(layer "F.Fab")
			(effects
				(font
					(size 1.27 1.27)
				)
			)
		)
		(duplicate_pad_numbers_are_jumpers no)
		(fp_line
			(start 0.299974 -0.150114)
			(end 0.299974 0.150114)
			(stroke
				(width 0.1)
				(type default)
			)
			(layer "F.Fab")
		)
		(fp_line
			(start -0.299974 -0.150114)
			(end 0.299974 -0.150114)
			(stroke
				(width 0.1)
				(type default)
			)
			(layer "F.Fab")
		)
		(fp_line
			(start 0.299974 0.150114)
			(end -0.299974 0.150114)
			(stroke
				(width 0.1)
				(type default)
			)
			(layer "F.Fab")
		)
		(fp_line
			(start -0.299974 0.150114)
			(end -0.299974 -0.150114)
			(stroke
				(width 0.1)
				(type default)
			)
			(layer "F.Fab")
		)
		(pad "1" smd rect
			(at -0.2667 0 90)
			(size 0.3048 0.381)
			(layers "F.Cu" "F.Mask" "F.Paste")
			(net "P5E_CPU0_G3_TX_C_DN<15>")
		)
		(pad "2" smd rect
			(at 0.2667 0 90)
			(size 0.3048 0.381)
			(layers "F.Cu" "F.Mask" "F.Paste")
			(net "P5E_CPU0_G3_TX_DN<15>")
		)
	)
	(footprint ""
		(layer "F.Cu")
		(at 84.27212 -44.42206 -90)
		(property "Reference" "U207"
			(at 1.57734 -2.028952 90)
			(unlocked yes)
			(layer "F.SilkS")
			(effects
				(font
					(size 0.7874 0.5842)
					(thickness 0.1524)
				)
				(justify left)
			)
		)
		(property "Value" ""
			(at 0 0 270)
			(layer "F.Fab")
			(effects
				(font
					(size 1.27 1.27)
				)
			)
		)
		(duplicate_pad_numbers_are_jumpers no)
		(fp_line
			(start -1.695958 1.124966)
			(end -1.695958 -1.124966)
			(stroke
				(width 0.1524)
				(type default)
			)
			(layer "F.SilkS")
		)
		(fp_line
			(start 1.695958 1.124966)
			(end -1.695958 1.124966)
			(stroke
				(width 0.1524)
				(type default)
			)
			(layer "F.SilkS")
		)
		(fp_line
			(start -1.695958 -1.124966)
			(end 1.695958 -1.124966)
			(stroke
				(width 0.1524)
				(type default)
			)
			(layer "F.SilkS")
		)
		(fp_line
			(start 1.695958 -1.124966)
			(end 1.695958 1.124966)
			(stroke
				(width 0.1524)
				(type default)
			)
			(layer "F.SilkS")
		)
		(fp_poly
			(pts
				(xy -2.43332 -0.484886) (xy -2.43332 -1.104646) (xy -1.81356 -0.794766)
			)
			(stroke
				(width 0)
				(type default)
			)
			(fill yes)
			(layer "F.SilkS")
		)
		(fp_line
			(start -0.674878 1.124966)
			(end -0.674878 -1.124966)
			(stroke
				(width 0.1)
				(type default)
			)
			(layer "F.Fab")
		)
		(fp_line
			(start 0.674878 1.124966)
			(end -0.674878 1.124966)
			(stroke
				(width 0.1)
				(type default)
			)
			(layer "F.Fab")
		)
		(fp_line
			(start -0.674878 -1.124966)
			(end 0.674878 -1.124966)
			(stroke
				(width 0.1)
				(type default)
			)
			(layer "F.Fab")
		)
		(fp_line
			(start 0.674878 -1.124966)
			(end 0.674878 1.124966)
			(stroke
				(width 0.1)
				(type default)
			)
			(layer "F.Fab")
		)
		(fp_poly
			(pts
				(xy -2.4892 -0.959866) (xy -1.86944 -0.649986) (xy -2.4892 -0.340106)
			)
			(stroke
				(width 0)
				(type default)
			)
			(fill yes)
			(layer "F.Fab")
		)
		(pad "1" smd rect
			(at -0.94488 -0.649986)
			(size 0.3556 1.2446)
			(layers "F.Cu" "F.Mask" "F.Paste")
			(net "Net_10784")
		)
		(pad "2" smd rect
			(at -0.94488 0)
			(size 0.3556 1.2446)
			(layers "F.Cu" "F.Mask" "F.Paste")
			(net "RST_PERST_OCP_V3_2_BUF_N")
		)
		(pad "3" smd rect
			(at -0.94488 0.649986)
			(size 0.3556 1.2446)
			(layers "F.Cu" "F.Mask" "F.Paste")
			(net "GND")
		)
		(pad "4" smd rect
			(at 0.94488 0.649986)
			(size 0.3556 1.2446)
			(layers "F.Cu" "F.Mask" "F.Paste")
			(net "RST_PERST_OCP_V3_2_BUF2_N")
		)
		(pad "5" smd rect
			(at 0.94488 -0.649986)
			(size 0.3556 1.2446)
			(layers "F.Cu" "F.Mask" "F.Paste")
			(net "P3V3_AUX")
		)
	)
)
